(kicad_pcb
	(version 20260206)
	(generator "pcbnew")
	(generator_version "10.0")
	(general
		(thickness 1.6)
		(legacy_teardrops no)
	)
	(paper "A4")
	(title_block
		(title "01162023_DA0F0TEBIF0_F0T_Expander_BD_F_brd_V02_OCP.brd")
		(comment 1 "Grand Teton / footprint 4451 of 9728 (PEX3), pads 1424-1536 of 2397")
	)
	(layers
		(0 "F.Cu" signal "TOP")
		(4 "In1.Cu" signal "GND")
		(6 "In2.Cu" signal "VCC")
		(8 "In3.Cu" signal "VCC1")
		(10 "In4.Cu" signal "GND1")
		(12 "In5.Cu" signal "IN1")
		(14 "In6.Cu" signal "GND2")
		(16 "In7.Cu" signal "IN2")
		(18 "In8.Cu" signal "GND3")
		(20 "In9.Cu" signal "IN3")
		(22 "In10.Cu" signal "GND4")
		(24 "In11.Cu" signal "IN4")
		(26 "In12.Cu" signal "GND5")
		(28 "In13.Cu" signal "IN5")
		(30 "In14.Cu" signal "GND6")
		(32 "In15.Cu" signal "IN6")
		(34 "In16.Cu" signal "GND7")
		(2 "B.Cu" signal "BOTTOM")
		(9 "F.Adhes" user "F.Adhesive")
		(11 "B.Adhes" user "B.Adhesive")
		(13 "F.Paste" user "Package Geometry/Pastemask Top")
		(15 "B.Paste" user "Package Geometry/Pastemask Bottom")
		(5 "F.SilkS" user "Ref Des/Silkscreen Top")
		(7 "B.SilkS" user "Ref Des/Silkscreen Bottom")
		(1 "F.Mask" user "Board Geometry/Soldermask Top")
		(3 "B.Mask" user "Board Geometry/Soldermask Bottom")
		(17 "Dwgs.User" user "User.Drawings")
		(19 "Cmts.User" user "User.Comments")
		(21 "Eco1.User" user "User.Eco1")
		(23 "Eco2.User" user "User.Eco2")
		(25 "Edge.Cuts" user "Board Geometry/Outline")
		(27 "Margin" user)
		(31 "F.CrtYd" user "Package Geometry/Place Bound Top")
		(29 "B.CrtYd" user "Package Geometry/Place Bound Bottom")
		(35 "F.Fab" user "Ref Des/Assembly Top")
		(33 "B.Fab" user "Ref Des/Assembly Bottom")
	)
	(footprint ""
		(layer "F.Cu")
		(at 407.949908 -295.89984)
		(property "Reference" "PEX3"
			(at -3.358642 35.5727 0)
			(unlocked yes)
			(layer "F.SilkS")
			(effects
				(font
					(size 2.032 1.524)
					(thickness 0.1524)
				)
				(justify left)
			)
		)
		(property "Value" ""
			(at 0 0 0)
			(layer "F.Fab")
			(effects
				(font
					(size 1.27 1.27)
				)
			)
		)
		(duplicate_pad_numbers_are_jumpers no)
		(pad "BH5" smd circle
			(at -18.999962 21.850096)
			(size 0.4572 0.4572)
			(layers "F.Cu" "F.Mask" "F.Paste")
			(net "Net_1512")
		)
		(pad "BH6" smd circle
			(at -18.050002 21.850096)
			(size 0.4572 0.4572)
			(layers "F.Cu" "F.Mask" "F.Paste")
			(net "GND")
		)
		(pad "BH7" smd circle
			(at -17.100042 21.850096)
			(size 0.4572 0.4572)
			(layers "F.Cu" "F.Mask" "F.Paste")
			(net "Net_1459")
		)
		(pad "BH8" smd circle
			(at -16.150082 21.850096)
			(size 0.4572 0.4572)
			(layers "F.Cu" "F.Mask" "F.Paste")
			(net "GND")
		)
		(pad "BH9" smd circle
			(at -15.200122 21.850096)
			(size 0.4572 0.4572)
			(layers "F.Cu" "F.Mask" "F.Paste")
			(net "P5E_PEX3_STN2_RX_DP<47>")
		)
		(pad "BH10" smd circle
			(at -14.249908 21.850096)
			(size 0.4572 0.4572)
			(layers "F.Cu" "F.Mask" "F.Paste")
			(net "GND")
		)
		(pad "BH11" smd circle
			(at -13.299948 21.850096)
			(size 0.4572 0.4572)
			(layers "F.Cu" "F.Mask" "F.Paste")
			(net "P5E_PEX3_STN2_RX_DP<45>")
		)
		(pad "BH12" smd circle
			(at -12.349988 21.850096)
			(size 0.4572 0.4572)
			(layers "F.Cu" "F.Mask" "F.Paste")
			(net "GND")
		)
		(pad "BH13" smd circle
			(at -11.400028 21.850096)
			(size 0.4572 0.4572)
			(layers "F.Cu" "F.Mask" "F.Paste")
			(net "P5E_PEX3_STN2_RX_DP<43>")
		)
		(pad "BH14" smd circle
			(at -10.450068 21.850096)
			(size 0.4572 0.4572)
			(layers "F.Cu" "F.Mask" "F.Paste")
			(net "GND")
		)
		(pad "BH15" smd circle
			(at -9.500108 21.850096)
			(size 0.4572 0.4572)
			(layers "F.Cu" "F.Mask" "F.Paste")
			(net "P5E_PEX3_STN2_RX_DP<41>")
		)
		(pad "BH16" smd circle
			(at -8.549894 21.850096)
			(size 0.4572 0.4572)
			(layers "F.Cu" "F.Mask" "F.Paste")
			(net "GND")
		)
		(pad "BH17" smd circle
			(at -7.599934 21.850096)
			(size 0.4572 0.4572)
			(layers "F.Cu" "F.Mask" "F.Paste")
			(net "P5E_PEX3_STN2_RX_DP<39>")
		)
		(pad "BH18" smd circle
			(at -6.649974 21.850096)
			(size 0.4572 0.4572)
			(layers "F.Cu" "F.Mask" "F.Paste")
			(net "GND")
		)
		(pad "BH19" smd circle
			(at -5.700014 21.850096)
			(size 0.4572 0.4572)
			(layers "F.Cu" "F.Mask" "F.Paste")
			(net "P5E_PEX3_STN2_RX_DP<37>")
		)
		(pad "BH20" smd circle
			(at -4.750054 21.850096)
			(size 0.4572 0.4572)
			(layers "F.Cu" "F.Mask" "F.Paste")
			(net "GND")
		)
		(pad "BH21" smd circle
			(at -3.800094 21.850096)
			(size 0.4572 0.4572)
			(layers "F.Cu" "F.Mask" "F.Paste")
			(net "P5E_PEX3_STN2_RX_DP<35>")
		)
		(pad "BH22" smd circle
			(at -2.84988 21.850096)
			(size 0.4572 0.4572)
			(layers "F.Cu" "F.Mask" "F.Paste")
			(net "GND")
		)
		(pad "BH23" smd circle
			(at -1.89992 21.850096)
			(size 0.4572 0.4572)
			(layers "F.Cu" "F.Mask" "F.Paste")
			(net "P5E_PEX3_STN2_RX_DP<33>")
		)
		(pad "BH24" smd circle
			(at -0.94996 21.850096)
			(size 0.4572 0.4572)
			(layers "F.Cu" "F.Mask" "F.Paste")
			(net "GND")
		)
		(pad "BH25" smd circle
			(at 0 21.850096)
			(size 0.4572 0.4572)
			(layers "F.Cu" "F.Mask" "F.Paste")
			(net "P5E_PEX3_STN1_RX_DP<16>")
		)
		(pad "BH26" smd circle
			(at 0.94996 21.850096)
			(size 0.4572 0.4572)
			(layers "F.Cu" "F.Mask" "F.Paste")
			(net "GND")
		)
		(pad "BH27" smd circle
			(at 1.89992 21.850096)
			(size 0.4572 0.4572)
			(layers "F.Cu" "F.Mask" "F.Paste")
			(net "P5E_PEX3_STN1_RX_DP<18>")
		)
		(pad "BH28" smd circle
			(at 2.84988 21.850096)
			(size 0.4572 0.4572)
			(layers "F.Cu" "F.Mask" "F.Paste")
			(net "GND")
		)
		(pad "BH29" smd circle
			(at 3.800094 21.850096)
			(size 0.4572 0.4572)
			(layers "F.Cu" "F.Mask" "F.Paste")
			(net "P5E_PEX3_STN1_RX_DP<20>")
		)
		(pad "BH30" smd circle
			(at 4.750054 21.850096)
			(size 0.4572 0.4572)
			(layers "F.Cu" "F.Mask" "F.Paste")
			(net "GND")
		)
		(pad "BH31" smd circle
			(at 5.700014 21.850096)
			(size 0.4572 0.4572)
			(layers "F.Cu" "F.Mask" "F.Paste")
			(net "P5E_PEX3_STN1_RX_DP<22>")
		)
		(pad "BH32" smd circle
			(at 6.649974 21.850096)
			(size 0.4572 0.4572)
			(layers "F.Cu" "F.Mask" "F.Paste")
			(net "GND")
		)
		(pad "BH33" smd circle
			(at 7.599934 21.850096)
			(size 0.4572 0.4572)
			(layers "F.Cu" "F.Mask" "F.Paste")
			(net "P5E_PEX3_STN1_RX_DP<24>")
		)
		(pad "BH34" smd circle
			(at 8.549894 21.850096)
			(size 0.4572 0.4572)
			(layers "F.Cu" "F.Mask" "F.Paste")
			(net "GND")
		)
		(pad "BH35" smd circle
			(at 9.500108 21.850096)
			(size 0.4572 0.4572)
			(layers "F.Cu" "F.Mask" "F.Paste")
			(net "P5E_PEX3_STN1_RX_DP<26>")
		)
		(pad "BH36" smd circle
			(at 10.450068 21.850096)
			(size 0.4572 0.4572)
			(layers "F.Cu" "F.Mask" "F.Paste")
			(net "GND")
		)
		(pad "BH37" smd circle
			(at 11.400028 21.850096)
			(size 0.4572 0.4572)
			(layers "F.Cu" "F.Mask" "F.Paste")
			(net "P5E_PEX3_STN1_RX_DP<28>")
		)
		(pad "BH38" smd circle
			(at 12.349988 21.850096)
			(size 0.4572 0.4572)
			(layers "F.Cu" "F.Mask" "F.Paste")
			(net "GND")
		)
		(pad "BH39" smd circle
			(at 13.299948 21.850096)
			(size 0.4572 0.4572)
			(layers "F.Cu" "F.Mask" "F.Paste")
			(net "P5E_PEX3_STN1_RX_DP<30>")
		)
		(pad "BH40" smd circle
			(at 14.249908 21.850096)
			(size 0.4572 0.4572)
			(layers "F.Cu" "F.Mask" "F.Paste")
			(net "GND")
		)
		(pad "BH41" smd circle
			(at 15.200122 21.850096)
			(size 0.4572 0.4572)
			(layers "F.Cu" "F.Mask" "F.Paste")
			(net "P5E_PEX3_STN0_RX_DP<15>")
		)
		(pad "BH42" smd circle
			(at 16.150082 21.850096)
			(size 0.4572 0.4572)
			(layers "F.Cu" "F.Mask" "F.Paste")
			(net "GND")
		)
		(pad "BH43" smd circle
			(at 17.100042 21.850096)
			(size 0.4572 0.4572)
			(layers "F.Cu" "F.Mask" "F.Paste")
			(net "P5E_PEX3_STN0_RX_DP<13>")
		)
		(pad "BH44" smd circle
			(at 18.050002 21.850096)
			(size 0.4572 0.4572)
			(layers "F.Cu" "F.Mask" "F.Paste")
			(net "GND")
		)
		(pad "BH45" smd circle
			(at 18.999962 21.850096)
			(size 0.4572 0.4572)
			(layers "F.Cu" "F.Mask" "F.Paste")
			(net "P5E_PEX3_STN0_RX_DP<11>")
		)
		(pad "BH46" smd circle
			(at 19.949922 21.850096)
			(size 0.4572 0.4572)
			(layers "F.Cu" "F.Mask" "F.Paste")
			(net "GND")
		)
		(pad "BH47" smd circle
			(at 20.899882 21.850096)
			(size 0.4572 0.4572)
			(layers "F.Cu" "F.Mask" "F.Paste")
			(net "P5E_PEX3_STN0_RX_DP<9>")
		)
		(pad "BH48" smd circle
			(at 21.850096 21.850096)
			(size 0.4572 0.4572)
			(layers "F.Cu" "F.Mask" "F.Paste")
			(net "GND")
		)
		(pad "BH49" smd circle
			(at 22.800056 21.850096)
			(size 0.4572 0.4572)
			(layers "F.Cu" "F.Mask" "F.Paste")
			(net "GND")
		)
		(pad "BJ2" smd circle
			(at -21.850096 22.800056)
			(size 0.4572 0.4572)
			(layers "F.Cu" "F.Mask" "F.Paste")
			(net "GND")
		)
		(pad "BJ3" smd circle
			(at -20.899882 22.800056)
			(size 0.4572 0.4572)
			(layers "F.Cu" "F.Mask" "F.Paste")
			(net "Net_1503")
		)
		(pad "BJ4" smd circle
			(at -19.949922 22.800056)
			(size 0.4572 0.4572)
			(layers "F.Cu" "F.Mask" "F.Paste")
			(net "GND")
		)
		(pad "BJ5" smd circle
			(at -18.999962 22.800056)
			(size 0.4572 0.4572)
			(layers "F.Cu" "F.Mask" "F.Paste")
			(net "Net_1475")
		)
		(pad "BJ6" smd circle
			(at -18.050002 22.800056)
			(size 0.4572 0.4572)
			(layers "F.Cu" "F.Mask" "F.Paste")
			(net "GND")
		)
		(pad "BJ7" smd circle
			(at -17.100042 22.800056)
			(size 0.4572 0.4572)
			(layers "F.Cu" "F.Mask" "F.Paste")
			(net "Net_1497")
		)
		(pad "BJ8" smd circle
			(at -16.150082 22.800056)
			(size 0.4572 0.4572)
			(layers "F.Cu" "F.Mask" "F.Paste")
			(net "GND")
		)
		(pad "BJ9" smd circle
			(at -15.200122 22.800056)
			(size 0.4572 0.4572)
			(layers "F.Cu" "F.Mask" "F.Paste")
			(net "P5E_PEX3_STN2_RX_DN<47>")
		)
		(pad "BJ10" smd circle
			(at -14.249908 22.800056)
			(size 0.4572 0.4572)
			(layers "F.Cu" "F.Mask" "F.Paste")
			(net "GND")
		)
		(pad "BJ11" smd circle
			(at -13.299948 22.800056)
			(size 0.4572 0.4572)
			(layers "F.Cu" "F.Mask" "F.Paste")
			(net "P5E_PEX3_STN2_RX_DN<45>")
		)
		(pad "BJ12" smd circle
			(at -12.349988 22.800056)
			(size 0.4572 0.4572)
			(layers "F.Cu" "F.Mask" "F.Paste")
			(net "GND")
		)
		(pad "BJ13" smd circle
			(at -11.400028 22.800056)
			(size 0.4572 0.4572)
			(layers "F.Cu" "F.Mask" "F.Paste")
			(net "P5E_PEX3_STN2_RX_DN<43>")
		)
		(pad "BJ14" smd circle
			(at -10.450068 22.800056)
			(size 0.4572 0.4572)
			(layers "F.Cu" "F.Mask" "F.Paste")
			(net "GND")
		)
		(pad "BJ15" smd circle
			(at -9.500108 22.800056)
			(size 0.4572 0.4572)
			(layers "F.Cu" "F.Mask" "F.Paste")
			(net "P5E_PEX3_STN2_RX_DN<41>")
		)
		(pad "BJ16" smd circle
			(at -8.549894 22.800056)
			(size 0.4572 0.4572)
			(layers "F.Cu" "F.Mask" "F.Paste")
			(net "GND")
		)
		(pad "BJ17" smd circle
			(at -7.599934 22.800056)
			(size 0.4572 0.4572)
			(layers "F.Cu" "F.Mask" "F.Paste")
			(net "P5E_PEX3_STN2_RX_DN<39>")
		)
		(pad "BJ18" smd circle
			(at -6.649974 22.800056)
			(size 0.4572 0.4572)
			(layers "F.Cu" "F.Mask" "F.Paste")
			(net "GND")
		)
		(pad "BJ19" smd circle
			(at -5.700014 22.800056)
			(size 0.4572 0.4572)
			(layers "F.Cu" "F.Mask" "F.Paste")
			(net "P5E_PEX3_STN2_RX_DN<37>")
		)
		(pad "BJ20" smd circle
			(at -4.750054 22.800056)
			(size 0.4572 0.4572)
			(layers "F.Cu" "F.Mask" "F.Paste")
			(net "GND")
		)
		(pad "BJ21" smd circle
			(at -3.800094 22.800056)
			(size 0.4572 0.4572)
			(layers "F.Cu" "F.Mask" "F.Paste")
			(net "P5E_PEX3_STN2_RX_DN<35>")
		)
		(pad "BJ22" smd circle
			(at -2.84988 22.800056)
			(size 0.4572 0.4572)
			(layers "F.Cu" "F.Mask" "F.Paste")
			(net "GND")
		)
		(pad "BJ23" smd circle
			(at -1.89992 22.800056)
			(size 0.4572 0.4572)
			(layers "F.Cu" "F.Mask" "F.Paste")
			(net "P5E_PEX3_STN2_RX_DN<33>")
		)
		(pad "BJ24" smd circle
			(at -0.94996 22.800056)
			(size 0.4572 0.4572)
			(layers "F.Cu" "F.Mask" "F.Paste")
			(net "GND")
		)
		(pad "BJ25" smd circle
			(at 0 22.800056)
			(size 0.4572 0.4572)
			(layers "F.Cu" "F.Mask" "F.Paste")
			(net "P5E_PEX3_STN1_RX_DN<16>")
		)
		(pad "BJ26" smd circle
			(at 0.94996 22.800056)
			(size 0.4572 0.4572)
			(layers "F.Cu" "F.Mask" "F.Paste")
			(net "GND")
		)
		(pad "BJ27" smd circle
			(at 1.89992 22.800056)
			(size 0.4572 0.4572)
			(layers "F.Cu" "F.Mask" "F.Paste")
			(net "P5E_PEX3_STN1_RX_DN<18>")
		)
		(pad "BJ28" smd circle
			(at 2.84988 22.800056)
			(size 0.4572 0.4572)
			(layers "F.Cu" "F.Mask" "F.Paste")
			(net "GND")
		)
		(pad "BJ29" smd circle
			(at 3.800094 22.800056)
			(size 0.4572 0.4572)
			(layers "F.Cu" "F.Mask" "F.Paste")
			(net "P5E_PEX3_STN1_RX_DN<20>")
		)
		(pad "BJ30" smd circle
			(at 4.750054 22.800056)
			(size 0.4572 0.4572)
			(layers "F.Cu" "F.Mask" "F.Paste")
			(net "GND")
		)
		(pad "BJ31" smd circle
			(at 5.700014 22.800056)
			(size 0.4572 0.4572)
			(layers "F.Cu" "F.Mask" "F.Paste")
			(net "P5E_PEX3_STN1_RX_DN<22>")
		)
		(pad "BJ32" smd circle
			(at 6.649974 22.800056)
			(size 0.4572 0.4572)
			(layers "F.Cu" "F.Mask" "F.Paste")
			(net "GND")
		)
		(pad "BJ33" smd circle
			(at 7.599934 22.800056)
			(size 0.4572 0.4572)
			(layers "F.Cu" "F.Mask" "F.Paste")
			(net "P5E_PEX3_STN1_RX_DN<24>")
		)
		(pad "BJ34" smd circle
			(at 8.549894 22.800056)
			(size 0.4572 0.4572)
			(layers "F.Cu" "F.Mask" "F.Paste")
			(net "GND")
		)
		(pad "BJ35" smd circle
			(at 9.500108 22.800056)
			(size 0.4572 0.4572)
			(layers "F.Cu" "F.Mask" "F.Paste")
			(net "P5E_PEX3_STN1_RX_DN<26>")
		)
		(pad "BJ36" smd circle
			(at 10.450068 22.800056)
			(size 0.4572 0.4572)
			(layers "F.Cu" "F.Mask" "F.Paste")
			(net "GND")
		)
		(pad "BJ37" smd circle
			(at 11.400028 22.800056)
			(size 0.4572 0.4572)
			(layers "F.Cu" "F.Mask" "F.Paste")
			(net "P5E_PEX3_STN1_RX_DN<28>")
		)
		(pad "BJ38" smd circle
			(at 12.349988 22.800056)
			(size 0.4572 0.4572)
			(layers "F.Cu" "F.Mask" "F.Paste")
			(net "GND")
		)
		(pad "BJ39" smd circle
			(at 13.299948 22.800056)
			(size 0.4572 0.4572)
			(layers "F.Cu" "F.Mask" "F.Paste")
			(net "P5E_PEX3_STN1_RX_DN<30>")
		)
		(pad "BJ40" smd circle
			(at 14.249908 22.800056)
			(size 0.4572 0.4572)
			(layers "F.Cu" "F.Mask" "F.Paste")
			(net "GND")
		)
		(pad "BJ41" smd circle
			(at 15.200122 22.800056)
			(size 0.4572 0.4572)
			(layers "F.Cu" "F.Mask" "F.Paste")
			(net "P5E_PEX3_STN0_RX_DN<15>")
		)
		(pad "BJ42" smd circle
			(at 16.150082 22.800056)
			(size 0.4572 0.4572)
			(layers "F.Cu" "F.Mask" "F.Paste")
			(net "GND")
		)
		(pad "BJ43" smd circle
			(at 17.100042 22.800056)
			(size 0.4572 0.4572)
			(layers "F.Cu" "F.Mask" "F.Paste")
			(net "P5E_PEX3_STN0_RX_DN<13>")
		)
		(pad "BJ44" smd circle
			(at 18.050002 22.800056)
			(size 0.4572 0.4572)
			(layers "F.Cu" "F.Mask" "F.Paste")
			(net "GND")
		)
		(pad "BJ45" smd circle
			(at 18.999962 22.800056)
			(size 0.4572 0.4572)
			(layers "F.Cu" "F.Mask" "F.Paste")
			(net "P5E_PEX3_STN0_RX_DN<11>")
		)
		(pad "BJ46" smd circle
			(at 19.949922 22.800056)
			(size 0.4572 0.4572)
			(layers "F.Cu" "F.Mask" "F.Paste")
			(net "GND")
		)
		(pad "BJ47" smd circle
			(at 20.899882 22.800056)
			(size 0.4572 0.4572)
			(layers "F.Cu" "F.Mask" "F.Paste")
			(net "P5E_PEX3_STN0_RX_DN<9>")
		)
		(pad "BJ48" smd circle
			(at 21.850096 22.800056)
			(size 0.4572 0.4572)
			(layers "F.Cu" "F.Mask" "F.Paste")
			(net "GND")
		)
		(pad "C1" smd circle
			(at -22.800056 -20.899882)
			(size 0.4572 0.4572)
			(layers "F.Cu" "F.Mask" "F.Paste")
			(net "P5E_PEX3_STN7_RX_DN<122>")
		)
		(pad "C2" smd circle
			(at -21.850096 -20.899882)
			(size 0.4572 0.4572)
			(layers "F.Cu" "F.Mask" "F.Paste")
			(net "P5E_PEX3_STN7_RX_DP<122>")
		)
		(pad "C3" smd circle
			(at -20.899882 -20.899882)
			(size 0.4572 0.4572)
			(layers "F.Cu" "F.Mask" "F.Paste")
			(net "GND")
		)
		(pad "C4" smd circle
			(at -19.949922 -20.899882)
			(size 0.4572 0.4572)
			(layers "F.Cu" "F.Mask" "F.Paste")
			(net "P5E_PEX3_STN7_RX_DN<124>")
		)
		(pad "C5" smd circle
			(at -18.999962 -20.899882)
			(size 0.4572 0.4572)
			(layers "F.Cu" "F.Mask" "F.Paste")
			(net "GND")
		)
		(pad "C6" smd circle
			(at -18.050002 -20.899882)
			(size 0.4572 0.4572)
			(layers "F.Cu" "F.Mask" "F.Paste")
			(net "P5E_PEX3_STN7_RX_DN<126>")
		)
		(pad "C7" smd circle
			(at -17.100042 -20.899882)
			(size 0.4572 0.4572)
			(layers "F.Cu" "F.Mask" "F.Paste")
			(net "GND")
		)
		(pad "C8" smd circle
			(at -16.150082 -20.899882)
			(size 0.4572 0.4572)
			(layers "F.Cu" "F.Mask" "F.Paste")
			(net "P5E_PEX3_STN6_RX_DN<111>")
		)
		(pad "C9" smd circle
			(at -15.200122 -20.899882)
			(size 0.4572 0.4572)
			(layers "F.Cu" "F.Mask" "F.Paste")
			(net "GND")
		)
		(pad "C10" smd circle
			(at -14.249908 -20.899882)
			(size 0.4572 0.4572)
			(layers "F.Cu" "F.Mask" "F.Paste")
			(net "P5E_PEX3_STN6_RX_DN<109>")
		)
		(pad "C11" smd circle
			(at -13.299948 -20.899882)
			(size 0.4572 0.4572)
			(layers "F.Cu" "F.Mask" "F.Paste")
			(net "GND")
		)
		(pad "C12" smd circle
			(at -12.349988 -20.899882)
			(size 0.4572 0.4572)
			(layers "F.Cu" "F.Mask" "F.Paste")
			(net "P5E_PEX3_STN6_RX_DN<107>")
		)
		(pad "C13" smd circle
			(at -11.400028 -20.899882)
			(size 0.4572 0.4572)
			(layers "F.Cu" "F.Mask" "F.Paste")
			(net "GND")
		)
		(pad "C14" smd circle
			(at -10.450068 -20.899882)
			(size 0.4572 0.4572)
			(layers "F.Cu" "F.Mask" "F.Paste")
			(net "P5E_PEX3_STN6_RX_DN<105>")
		)
		(pad "C15" smd circle
			(at -9.500108 -20.899882)
			(size 0.4572 0.4572)
			(layers "F.Cu" "F.Mask" "F.Paste")
			(net "GND")
		)
		(pad "C16" smd circle
			(at -8.549894 -20.899882)
			(size 0.4572 0.4572)
			(layers "F.Cu" "F.Mask" "F.Paste")
			(net "P5E_PEX3_STN6_RX_DN<103>")
		)
		(pad "C17" smd circle
			(at -7.599934 -20.899882)
			(size 0.4572 0.4572)
			(layers "F.Cu" "F.Mask" "F.Paste")
			(net "GND")
		)
		(pad "C18" smd circle
			(at -6.649974 -20.899882)
			(size 0.4572 0.4572)
			(layers "F.Cu" "F.Mask" "F.Paste")
			(net "P5E_PEX3_STN6_RX_DN<101>")
		)
		(pad "C19" smd circle
			(at -5.700014 -20.899882)
			(size 0.4572 0.4572)
			(layers "F.Cu" "F.Mask" "F.Paste")
			(net "GND")
		)
		(pad "C20" smd circle
			(at -4.750054 -20.899882)
			(size 0.4572 0.4572)
			(layers "F.Cu" "F.Mask" "F.Paste")
			(net "P5E_PEX3_STN6_RX_DN<99>")
		)
		(pad "C21" smd circle
			(at -3.800094 -20.899882)
			(size 0.4572 0.4572)
			(layers "F.Cu" "F.Mask" "F.Paste")
			(net "GND")
		)
	)
)
